# T6G (Grand Teton) — schematic parts with pin connectivity, parts 1903–2072 of 8303; source: Cadence DE-HDL packaged netlist (pstxprt.dat, pstxnet.dat, pstchip.dat)

C2655  Q_CAP  22UF 4V 20% X6S  pkg C0402  page 70 : 1 = PVDDIO_P0 ; 2 = GND
C2656  Q_CAP  22UF 4V 20% X6S  pkg C0402  page 70 : 1 = PVDD11_S3_P0 ; 2 = GND
C2657  Q_CAP  22UF 4V 20% X6S  pkg C0402  page 70 : 1 = PVDD11_S3_P0 ; 2 = GND
C2658  Q_CAP  22UF 4V 20% X6S  pkg C0402  page 70 : 1 = PVDD11_S3_P0 ; 2 = GND
C2659  Q_CAP  10UF 6.3V 20% X6S  pkg C0402  page 75 : 1 = PVDD_33_S5 ; 2 = GND
C2660  Q_CAP  22UF 4V 20% X6S  pkg C0402  page 75 : 1 = PVDD18_S5_P1 ; 2 = GND
C2661  Q_CAP  22UF 4V 20% X6S  pkg C0402  page 75 : 1 = PVDD18_S5_P1 ; 2 = GND
C2662  Q_CAP  10UF 6.3V 20% X6S  pkg C0402  page 75 : 1 = PVDD_33_S5 ; 2 = GND
C2663  Q_CAP  22UF 4V 20% X6S  pkg C0402  page 75 : 1 = PVDD18_S5_P1 ; 2 = GND
C2664  Q_CAP  22UF 4V 20% X6S  pkg C0402  page 75 : 1 = PVDD18_S5_P1 ; 2 = GND
C2665  Q_CAP  22UF 4V 20% X6S  pkg C0402  page 75 : 1 = PVDD18_S5_P1 ; 2 = GND
C2667  Q_CAP  22UF 4V 20% X6S  pkg C0402  page 75 : 1 = PVDD18_S5_P1 ; 2 = GND
C2668  Q_CAP  22UF 4V 20% X6S  pkg C0402  page 75 : 1 = PVDD18_S5_P1 ; 2 = GND
C2669  Q_CAP  22UF 4V 20% X6S  pkg C0402  page 75 : 1 = PVDD18_S5_P1 ; 2 = GND
C2670  Q_CAP  22UF 4V 20% X6S  pkg C0402  page 75 : 1 = PVDD18_S5_P1 ; 2 = GND
C2671  Q_CAP  22UF 4V 20% X6S  pkg C0402  page 75 : 1 = PVDD18_S5_P1 ; 2 = GND
C2672  Q_CAP  22UF 4V 20% X6S  pkg C0402  page 75 : 1 = PVDD18_S5_P1 ; 2 = GND
C2673  Q_CAP  22UF 4V 20% X6S  pkg C0402  page 75 : 1 = PVDD18_S5_P1 ; 2 = GND
C3888  Q_CAP  22UF 4V 20% X6S  pkg C0402  page 68 : 1 = PVDDCR_SOC_P0 ; 2 = GND
C3889  Q_CAP  22UF 4V 20% X6S  pkg C0402  page 68 : 1 = PVDDCR_SOC_P0 ; 2 = GND
C3890  Q_CAP  22UF 4V 20% X6S  pkg C0402  page 68 : 1 = PVDD11_S3_P0 ; 2 = GND
C3891  Q_CAP  22UF 4V 20% X6S  pkg C0402  page 68 : 1 = PVDD11_S3_P0 ; 2 = GND
C3892  Q_CAP  22UF 4V 20% X6S  pkg C0402  page 68 : 1 = PVDD11_S3_P0 ; 2 = GND
C3893  Q_CAP  22UF 4V 20% X6S  pkg C0402  page 68 : 1 = PVDD11_S3_P0 ; 2 = GND
C3894  Q_CAP  22UF 4V 20% X6S  pkg C0402  page 68 : 1 = PVDDCR_SOC_P0 ; 2 = GND
C3895  Q_CAP  22UF 4V 20% X6S  pkg C0402  page 68 : 1 = PVDDCR_SOC_P0 ; 2 = GND
C3896  Q_CAP  22UF 4V 20% X6S  pkg C0402  page 68 : 1 = PVDDCR_SOC_P0 ; 2 = GND
C3897  Q_CAP  22UF 4V 20% X6S  pkg C0402  page 68 : 1 = PVDD18_S5_P0 ; 2 = GND
C3898  Q_CAP  22UF 4V 20% X6S  pkg C0402  page 68 : 1 = PVDDIO_P0 ; 2 = GND
C3899  Q_CAP  22UF 4V 20% X6S  pkg C0402  page 68 : 1 = PVDDIO_P0 ; 2 = GND
C3900  Q_CAP  22UF 4V 20% X6S  pkg C0402  page 72 : 1 = PVDDCR_SOC_P1 ; 2 = GND
C3901  Q_CAP  22UF 4V 20% X6S  pkg C0402  page 72 : 1 = PVDDCR_SOC_P1 ; 2 = GND
C3902  Q_CAP  22UF 4V 20% X6S  pkg C0402  page 72 : 1 = PVDD11_S3_P1 ; 2 = GND
C3903  Q_CAP  22UF 4V 20% X6S  pkg C0402  page 72 : 1 = PVDD11_S3_P1 ; 2 = GND
C3904  Q_CAP  22UF 4V 20% X6S  pkg C0402  page 72 : 1 = PVDD11_S3_P1 ; 2 = GND
C3905  Q_CAP  22UF 4V 20% X6S  pkg C0402  page 72 : 1 = PVDD11_S3_P1 ; 2 = GND
C3906  Q_CAP  22UF 4V 20% X6S  pkg C0402  page 72 : 1 = PVDDCR_SOC_P1 ; 2 = GND
C3907  Q_CAP  22UF 4V 20% X6S  pkg C0402  page 72 : 1 = PVDDCR_SOC_P1 ; 2 = GND
C3908  Q_CAP  22UF 4V 20% X6S  pkg C0402  page 72 : 1 = PVDDCR_SOC_P1 ; 2 = GND
C3909  Q_CAP  22UF 4V 20% X6S  pkg C0402  page 72 : 1 = PVDD18_S5_P1 ; 2 = GND
C3910  Q_CAP  22UF 4V 20% X6S  pkg C0402  page 72 : 1 = PVDDIO_P1 ; 2 = GND
C3911  Q_CAP  22UF 4V 20% X6S  pkg C0402  page 72 : 1 = PVDDIO_P1 ; 2 = GND
C3912  Q_CAP  22UF 4V 20% X6S  pkg C0402  page 74 : 1 = PVDDCR_SOC_P1 ; 2 = GND
C3913  Q_CAP  22UF 4V 20% X6S  pkg C0402  page 74 : 1 = PVDDCR_SOC_P1 ; 2 = GND
C3914  Q_CAP  22UF 4V 20% X6S  pkg C0402  page 74 : 1 = PVDDCR_SOC_P1 ; 2 = GND
C3915  Q_CAP  22UF 4V 20% X6S  pkg C0402  page 74 : 1 = PVDDCR_SOC_P1 ; 2 = GND
C3916  Q_CAP  22UF 4V 20% X6S  pkg C0402  page 74 : 1 = PVDDCR_SOC_P1 ; 2 = GND
C3917  Q_CAP  22UF 4V 20% X6S  pkg C0402  page 74 : 1 = PVDDCR_SOC_P1 ; 2 = GND
C3918  Q_CAP  22UF 4V 20% X6S  pkg C0402  page 74 : 1 = PVDDCR_SOC_P1 ; 2 = GND
C3919  Q_CAP  22UF 4V 20% X6S  pkg C0402  page 74 : 1 = PVDD11_S3_P1 ; 2 = GND
C3920  Q_CAP  22UF 4V 20% X6S  pkg C0402  page 74 : 1 = PVDD11_S3_P1 ; 2 = GND
C3921  Q_CAP  22UF 4V 20% X6S  pkg C0402  page 74 : 1 = PVDD11_S3_P1 ; 2 = GND
C3922  Q_CAP  22UF 4V 20% X6S  pkg C0402  page 74 : 1 = PVDD11_S3_P1 ; 2 = GND
C3925  Q_CAP  22UF 4V 20% X6S  pkg C0402  page 70 : 1 = PVDDCR_SOC_P0 ; 2 = GND
C3926  Q_CAP  22UF 4V 20% X6S  pkg C0402  page 70 : 1 = PVDDCR_SOC_P0 ; 2 = GND
C3927  Q_CAP  22UF 4V 20% X6S  pkg C0402  page 70 : 1 = PVDDCR_SOC_P0 ; 2 = GND
C3928  Q_CAP  22UF 4V 20% X6S  pkg C0402  page 70 : 1 = PVDDCR_SOC_P0 ; 2 = GND
C3929  Q_CAP  22UF 4V 20% X6S  pkg C0402  page 70 : 1 = PVDDCR_SOC_P0 ; 2 = GND
C3930  Q_CAP  22UF 4V 20% X6S  pkg C0402  page 70 : 1 = PVDDCR_SOC_P0 ; 2 = GND
C3931  Q_CAP  22UF 4V 20% X6S  pkg C0402  page 70 : 1 = PVDDCR_SOC_P0 ; 2 = GND
C3932  Q_CAP  22UF 4V 20% X6S  pkg C0402  page 70 : 1 = PVDD11_S3_P0 ; 2 = GND
C3933  Q_CAP  22UF 4V 20% X6S  pkg C0402  page 70 : 1 = PVDD11_S3_P0 ; 2 = GND
C3934  Q_CAP  22UF 4V 20% X6S  pkg C0402  page 70 : 1 = PVDD11_S3_P0 ; 2 = GND
C3935  Q_CAP  22UF 4V 20% X6S  pkg C0402  page 70 : 1 = PVDD11_S3_P0 ; 2 = GND
C4178  Q_CAP  22UF 4V 20% X6S  pkg C0402  page 69 : 1 = PVDDCR_CPU0_P0 ; 2 = GND
C4179  Q_CAP  22UF 4V 20% X6S  pkg C0402  page 69 : 1 = PVDDCR_CPU0_P0 ; 2 = GND
C5000  Q_CAP  1000PF 50V 5% X7R  pkg 0402  page 34 : 1 = FM_BIOS_POST_CMPLT_BUF_N ; 2 = GND
C5001  Q_CAP  1000PF 50V 5% X7R  pkg 0402  page 209 : 1 = FM_PWRGD_PVDD18_S5_P0 ; 2 = GND
C5002  Q_CAP  1000PF 50V 5% X7R  pkg 0402  page 192 : 1 = FM_PWRGD_PVDD33_S5 ; 2 = GND
C5003  Q_CAP  1000PF 50V 5% X7R  pkg 0402  page 210 : 1 = GND ; 2 = PWRGD_PVDDCR_CPU0_P1
C5004  Q_CAP  1000PF 50V 5% X7R  pkg 0402  page 200 : 1 = GND ; 2 = PWRGD_PVDDCR_CPU1_P0
C5005  Q_CAP  1000PF 50V 5% X7R  pkg 0402  page 200 : 1 = GND ; 2 = PWRGD_PVDDIO_P0
C5006  Q_CAP  1000PF 50V 5% X7R  pkg 0402  page 217 : 1 = GND ; 2 = PWRGD_PVDDIO_P1
C5009  Q_CAP  1000PF 50V 5% X7R  pkg 0402  page 207 : 1 = PVDD11_S3_P0_PMALERT ; 2 = GND
C5010  Q_CAP  1000PF 50V 5% X7R  pkg 0402  page 224 : 1 = PVDD11_S3_P1_PMALERT ; 2 = GND
C5011  Q_CAP  1000PF 50V 5% X7R  pkg 0402  page 193 : 1 = PVDDCR_CPU0_P0_PMALERT ; 2 = GND
C5012  Q_CAP  1000PF 50V 5% X7R  pkg 0402  page 210 : 1 = PVDDCR_CPU0_P1_PMALERT ; 2 = GND
C5013  Q_CAP  1000PF 50V 5% X7R  pkg 0402  page 200 : 1 = PVDDCR_CPU1_P0_SMB_ALERT ; 2 = GND
C5014  Q_CAP  1000PF 50V 5% X7R  pkg 0402  page 259 : 1 = PWRGD_P12V_MEM_R ; 2 = GND
C5015  Q_CAP  1000PF 50V 5% EMPTY  pkg 0402  page 190 : 1 = PWRGD_P3V3_AUX ; 2 = GND
C5016  Q_CAP  1000PF 50V 5% X7R  pkg 0402  page 226 : 1 = PWRGD_PVDD18_S5_R_P1 ; 2 = GND
C5017  Q_CAP  1000PF 50V 5% X7R  pkg 0402  page 193 : 1 = GND ; 2 = PWRGD_PVDDCR_CPU0_P0
C5018  Q_CAP  1000PF 50V 5% X7R  pkg 0402  page 193 : 1 = GND ; 2 = PWRGD_PVDDCR_SOC_P0
C5019  Q_CAP  1000PF 50V 5% X7R  pkg 0402  page 210 : 1 = GND ; 2 = PWRGD_PVDDCR_SOC_P1
C5020  Q_CAP  1000PF 50V 5% X7R  pkg 0402  page 217 : 1 = GND ; 2 = PVDDCR_CPU1_P1_SMB_ALERT
C5022  Q_CAP  1000PF 50V 5% X7R  pkg 0402  page 217 : 1 = GND ; 2 = PWRGD_PVDDCR_CPU1_P1
C5023  Q_CAP  1000PF 50V 5% X7R  pkg 0402  page 28 : 1 = RST_CPU0_RSMRST_N ; 2 = GND
C5024  Q_CAP  1000PF 50V 5% X7R  pkg 0402  page 55 : 1 = RST_CPU1_RSMRST_N ; 2 = GND
C5032  Q_CAP  10UF 25V 10% X6S  pkg C0805  page 187 : 1 = P1V5_BAT ; 2 = GND
C5229  Q_CAP  1UF 25V 10% EMPTY  pkg C0402  page 234 : 1 = P3V3_AUX ; 2 = GND
C5232  Q_CAP  0.1UF 25V 10% EMPTY  pkg C0402  page 234 : 1 = PD_U5201_RSTN ; 2 = GND
C5234  Q_CAP  0.1UF 25V 10% EMPTY  pkg C0402  page 234 : 1 = P3V3_AUX ; 2 = GND
C5236  Q_CAP  0.1UF 25V 10% EMPTY  pkg C0402  page 234 : 1 = PD_U5201_VREG ; 2 = GND
C6000  Q_CAP  0.1UF 25V 10% X7R  pkg 0402  page 150 : 1 = SCM_VDD_RTC ; 2 = GND
C6003  Q_CAP  0.1UF 25V 10% X7R  pkg 0402  page 180 : 1 = USB3_CPU0_BMC_TX_DP ; 2 = USB3_CPU0_BMC_TX_C1_DP
C6004  Q_CAP  0.1UF 25V 10% X7R  pkg 0402  page 180 : 1 = USB3_CPU0_BMC_TX_DN ; 2 = USB3_CPU0_BMC_TX_C1_DN
C6005  Q_CAP  0.1UF 25V 10% X7R  pkg 0402  page 113 : 1 = P2E_MB_BMC_TX_BUF2_DP<0> ; 2 = P2E_MB_BMC_TX_BUF_C_DP<0>
C6006  Q_CAP  0.1UF 25V 10% X7R  pkg 0402  page 113 : 1 = P2E_MB_BMC_TX_BUF2_DN<0> ; 2 = P2E_MB_BMC_TX_BUF_C_DN<0>
C6007  Q_CAP  0.1UF 25V 10% X7R  pkg 0402  page 113 : 1 = P2E_MB_BMC_RX_BUF2_C_DP<0> ; 2 = P2E_MB_BMC_RX_BUF_DP<0>
C6008  Q_CAP  0.1UF 25V 10% X7R  pkg 0402  page 113 : 1 = P2E_MB_BMC_RX_BUF2_C_DN<0> ; 2 = P2E_MB_BMC_RX_BUF_DN<0>
C6009  Q_CAP  1UF 25V 10% X6S  pkg C0402  page 112 : 1 = P3V3_AUX ; 2 = GND
C6010  Q_CAP  10UF 16V 10% X6S  pkg C0805  page 112 : 1 = P3V3_AUX ; 2 = GND
C6011  Q_CAP  0.1UF 25V 10% X7R  pkg 0402  page 112 : 1 = BUF2_VDD ; 2 = GND
C6012  Q_CAP  0.1UF 25V 10% X7R  pkg 0402  page 112 : 1 = BUF2_VDD ; 2 = GND
C6013  Q_CAP  0.1UF 25V 10% X7R  pkg 0402  page 180 : 1 = USB3_CPU0_BMC_TX_DP ; 2 = USB3_CPU0_BMC_TX_C2_DP
C6014  Q_CAP  0.1UF 25V 10% X7R  pkg 0402  page 180 : 1 = USB3_CPU0_BMC_TX_DN ; 2 = USB3_CPU0_BMC_TX_C2_DN
C6015  Q_CAP_DIFFBUS  DIFF BUS_0.33UF 6.3V 10% X6S  pkg C0402  page 180 : 1 = USB3_CPU0_BMC_RX_HUB1_DP ; 2 = USB3_CPU0_BMC_RX_HUB_C_DP
C6016  Q_CAP_DIFFBUS  DIFF BUS_0.33UF 6.3V 10% X6S  pkg C0402  page 180 : 1 = USB3_CPU0_BMC_RX_HUB1_DN ; 2 = USB3_CPU0_BMC_RX_HUB_C_DN
C6017  Q_CAP  0.1UF 25V 10% X7R  pkg 0402  page 180 : 1 = USB3_CPU0_BMC_RX_HUB2_DP ; 2 = USB3_CPU0_BMC_RX_HUB_C_DP
C6018  Q_CAP  0.1UF 25V 10% X7R  pkg 0402  page 180 : 1 = USB3_CPU0_BMC_RX_HUB2_DN ; 2 = USB3_CPU0_BMC_RX_HUB_C_DN
C6019  Q_CAP_DIFFBUS  DIFF BUS_0.33UF 6.3V 10% X6S  pkg C0402  page 180 : 1 = USB3_CPU0_BMC_RX_DP ; 2 = USB3_CPU0_BMC_RX_C1_DP
C6020  Q_CAP_DIFFBUS  DIFF BUS_0.33UF 6.3V 10% X6S  pkg C0402  page 180 : 1 = USB3_CPU0_BMC_RX_DN ; 2 = USB3_CPU0_BMC_RX_C1_DN
C6021  Q_CAP_DIFFBUS  DIFF BUS_0.33UF 6.3V 10% X6S  pkg C0402  page 180 : 1 = USB3_CPU0_BMC_RX_DP ; 2 = USB3_CPU0_BMC_RX_C2_DP
C6022  Q_CAP_DIFFBUS  DIFF BUS_0.33UF 6.3V 10% X6S  pkg C0402  page 180 : 1 = USB3_CPU0_BMC_RX_DN ; 2 = USB3_CPU0_BMC_RX_C2_DN
C6023  Q_CAP  0.1UF 25V 10% X7R  pkg 0402  page 180 : 1 = USB3_CPU0_BMC_HUB1_TX_DP ; 2 = USB3_CPU0_BMC_TX_BUF_C_DP
C6024  Q_CAP  0.1UF 25V 10% X7R  pkg 0402  page 180 : 1 = USB3_CPU0_BMC_HUB1_TX_DN ; 2 = USB3_CPU0_BMC_TX_BUF_C_DN
C6025  Q_CAP  0.1UF 25V 10% X7R  pkg 0402  page 180 : 1 = USB3_CPU0_BMC_HUB2_TX_DP ; 2 = USB3_CPU0_BMC_TX_BUF_C_DP
C6026  Q_CAP  0.1UF 25V 10% X7R  pkg 0402  page 180 : 1 = USB3_CPU0_BMC_HUB2_TX_DN ; 2 = USB3_CPU0_BMC_TX_BUF_C_DN
C6027  Q_CAP  22UF 16V 20% X6S  pkg C0805  page 176 : 1 = P5V_AUX ; 2 = GND
C6028  Q_CAP  470PF 50V 10% X7R  pkg 0402  page 176 : 1 = P5V_AUX ; 2 = GND
C6030  Q_CAP  22UF 6.3V 20% X6S  pkg C0603  page 177 : 1 = P1V2_CPU0_USB_DVDD12 ; 2 = GND
C6031  Q_CAP  1UF 25V 10% X6S  pkg C0402  page 177 : 1 = P1V2_CPU0_USB_DVDD12 ; 2 = GND
C6032  Q_CAP  0.1UF 25V 10% X7R  pkg 0402  page 177 : 1 = P1V2_CPU0_USB_DVDD12 ; 2 = GND
C6033  Q_CAP  0.01UF 50V 10% X7R  pkg C0402  page 177 : 1 = P1V2_CPU0_USB_DVDD12 ; 2 = GND
C6034  Q_CAP  0.1UF 25V 10% X7R  pkg 0402  page 177 : 1 = P1V2_CPU0_USB_DVDD12 ; 2 = GND
C6035  Q_CAP  0.01UF 50V 10% X7R  pkg C0402  page 177 : 1 = P1V2_CPU0_USB_DVDD12 ; 2 = GND
C6036  Q_CAP  0.1UF 25V 10% X7R  pkg 0402  page 177 : 1 = P1V2_CPU0_USB_DVDD12 ; 2 = GND
C6037  Q_CAP  0.01UF 50V 10% X7R  pkg C0402  page 177 : 1 = P1V2_CPU0_USB_DVDD12 ; 2 = GND
C6038  Q_CAP  0.1UF 25V 10% X7R  pkg 0402  page 177 : 1 = P1V2_CPU0_USB_DVDD12 ; 2 = GND
C6039  Q_CAP  0.01UF 50V 10% X7R  pkg C0402  page 177 : 1 = P1V2_CPU0_USB_DVDD12 ; 2 = GND
C6040  Q_CAP  0.01UF 50V 10% X7R  pkg C0402  page 177 : 1 = P3V3_AUX ; 2 = GND
C6041  Q_CAP  0.1UF 25V 10% X7R  pkg 0402  page 177 : 1 = P3V3_AUX ; 2 = GND
C6042  Q_CAP  22UF 6.3V 20% X6S  pkg C0603  page 177 : 1 = P3V3_AUX_CPU0_USB_AVDD33 ; 2 = GND
C6043  Q_CAP  1UF 25V 10% X6S  pkg C0402  page 177 : 1 = P3V3_AUX_CPU0_USB_AVDD33 ; 2 = GND
C6044  Q_CAP  0.1UF 25V 10% X7R  pkg 0402  page 177 : 1 = P3V3_AUX_CPU0_USB_AVDD33 ; 2 = GND
C6045  Q_CAP  0.01UF 50V 10% X7R  pkg C0402  page 177 : 1 = P3V3_AUX_CPU0_USB_AVDD33 ; 2 = GND
C6046  Q_CAP  22UF 6.3V 20% X6S  pkg C0603  page 177 : 1 = P3V3_AUX ; 2 = GND
C6047  Q_CAP  1UF 25V 10% X6S  pkg C0402  page 177 : 1 = P3V3_AUX ; 2 = GND
C6048  Q_CAP  0.1UF 25V 10% X7R  pkg 0402  page 177 : 1 = P3V3_AUX ; 2 = GND
C6049  Q_CAP  0.01UF 50V 10% X7R  pkg C0402  page 177 : 1 = P3V3_AUX ; 2 = GND
C6050  Q_CAP  0.1UF 25V 10% X7R  pkg 0402  page 177 : 1 = P3V3_AUX ; 2 = GND
C6051  Q_CAP  0.01UF 50V 10% X7R  pkg C0402  page 177 : 1 = P3V3_AUX ; 2 = GND
C6052  Q_CAP  0.1UF 25V 10% X7R  pkg 0402  page 177 : 1 = P3V3_AUX ; 2 = GND
C6053  Q_CAP  0.01UF 50V 10% X7R  pkg C0402  page 177 : 1 = P3V3_AUX ; 2 = GND
C6054  Q_CAP  0.001UF 50V 10% X7R  pkg C0402  page 177 : 1 = P1V2_AUX ; 2 = GND
C6055  Q_CAP  0.01UF 50V 10% X7R  pkg C0402  page 177 : 1 = P1V2_AUX ; 2 = GND
C6056  Q_CAP  0.001UF 50V 10% X7R  pkg C0402  page 177 : 1 = P1V2_AUX ; 2 = GND
C6057  Q_CAP  0.01UF 50V 10% X7R  pkg C0402  page 177 : 1 = P1V2_AUX ; 2 = GND
C6058  Q_CAP  0.001UF 50V 10% X7R  pkg C0402  page 177 : 1 = P1V2_AUX ; 2 = GND
C6059  Q_CAP  0.01UF 50V 10% X7R  pkg C0402  page 177 : 1 = P1V2_AUX ; 2 = GND
C6060  Q_CAP  0.001UF 50V 10% X7R  pkg C0402  page 177 : 1 = P1V2_AUX ; 2 = GND
C6061  Q_CAP  0.01UF 50V 10% X7R  pkg C0402  page 177 : 1 = P1V2_AUX ; 2 = GND
C6062  Q_CAP  0.001UF 50V 10% X7R  pkg C0402  page 177 : 1 = P1V2_AUX ; 2 = GND
C6063  Q_CAP  0.01UF 50V 10% X7R  pkg C0402  page 177 : 1 = P1V2_AUX ; 2 = GND
C6064  Q_CAP  0.1UF 25V 10% X7R  pkg 0402  page 177 : 1 = P1V2_AUX ; 2 = GND
C6065  Q_CAP  1UF 25V 10% X6S  pkg C0402  page 177 : 1 = P1V2_AUX ; 2 = GND
C6066  Q_CAP  22UF 6.3V 20% X6S  pkg C0603  page 177 : 1 = P1V2_AUX ; 2 = GND
C6067  Q_CAP  0.001UF 50V 10% X7R  pkg C0402  page 177 : 1 = P1V2_AUX ; 2 = GND
C6068  Q_CAP  0.01UF 50V 10% X7R  pkg C0402  page 177 : 1 = P1V2_AUX ; 2 = GND
C6069  Q_CAP  0.001UF 50V 10% X7R  pkg C0402  page 177 : 1 = P1V2_AUX ; 2 = GND
C6070  Q_CAP  0.01UF 50V 10% X7R  pkg C0402  page 177 : 1 = P1V2_AUX ; 2 = GND
C6071  Q_CAP  0.001UF 50V 10% X7R  pkg C0402  page 177 : 1 = P1V2_AUX ; 2 = GND
C6072  Q_CAP  0.01UF 50V 10% X7R  pkg C0402  page 177 : 1 = P1V2_AUX ; 2 = GND
C6073  Q_CAP  0.001UF 50V 10% X7R  pkg C0402  page 177 : 1 = P1V2_AUX ; 2 = GND
C6074  Q_CAP  0.01UF 50V 10% X7R  pkg C0402  page 177 : 1 = P1V2_AUX ; 2 = GND
C6075  Q_CAP  0.001UF 50V 10% X7R  pkg C0402  page 177 : 1 = P1V2_AUX ; 2 = GND
C6076  Q_CAP  0.01UF 50V 10% X7R  pkg C0402  page 177 : 1 = P1V2_AUX ; 2 = GND
C6077  Q_CAP  0.1UF 25V 10% X7R  pkg 0402  page 177 : 1 = P1V2_AUX ; 2 = GND
C6078  Q_CAP  1UF 25V 10% X6S  pkg C0402  page 177 : 1 = P1V2_AUX ; 2 = GND
C6079  Q_CAP  22UF 6.3V 20% X6S  pkg C0603  page 177 : 1 = P1V2_AUX ; 2 = GND
